(kicad_pcb
	(version 20241229)
	(generator "pcbnew")
	(generator_version "9.0")
	(general
		(thickness 1.6)
		(legacy_teardrops no)
	)
	(paper "A4")
	(title_block
		(title "GMSL Deserializer")
		(date "2025-10-09")
		(rev "1.0.4")
		(company "Antmicro Ltd")
		(comment 1 "www.antmicro.com")
		(comment 9 "footprints 1-7 of 235")
	)
	(layers
		(0 "F.Cu" signal)
		(4 "In1.Cu" power)
		(6 "In2.Cu" power)
		(2 "B.Cu" signal)
		(9 "F.Adhes" user "F.Adhesive")
		(11 "B.Adhes" user "B.Adhesive")
		(13 "F.Paste" user)
		(15 "B.Paste" user)
		(5 "F.SilkS" user "F.Silkscreen")
		(7 "B.SilkS" user "B.Silkscreen")
		(1 "F.Mask" user)
		(3 "B.Mask" user)
		(17 "Dwgs.User" user "User.Drawings")
		(19 "Cmts.User" user "User.Comments")
		(21 "Eco1.User" user "User.Eco1")
		(23 "Eco2.User" user "User.Eco2")
		(25 "Edge.Cuts" user)
		(27 "Margin" user)
		(31 "F.CrtYd" user "F.Courtyard")
		(29 "B.CrtYd" user "B.Courtyard")
		(35 "F.Fab" user)
		(33 "B.Fab" user)
	)
	(footprint "antmicro-footprints:SOD-523_NP"
		(layer "F.Cu")
		(at 187.198 56.261)
		(property "Reference" "D11"
			(at 0.848 0.45 0)
			(layer "F.SilkS")
			(effects
				(font
					(size 0.7 0.7)
					(thickness 0.15)
				)
				(justify left bottom)
			)
		)
		(property "Value" "ESD5B5_0ST1G"
			(at 0 1.499 0)
			(layer "F.Fab")
			(effects
				(font
					(size 0.7 0.7)
					(thickness 0.15)
				)
				(justify left bottom)
			)
		)
		(property "Datasheet" "https://www.onsemi.com/pdf/datasheet/esd5b5.0st1-d.pdf"
			(at 0 0 0)
			(layer "F.Fab")
			(hide yes)
			(effects
				(font
					(size 1.27 1.27)
					(thickness 0.15)
				)
			)
		)
		(property "Description" "Bidirectional TVS, 30 kV,  SOD-523, 5 V, 32 pF"
			(at 0 0 0)
			(layer "F.Fab")
			(hide yes)
			(effects
				(font
					(size 1.27 1.27)
					(thickness 0.15)
				)
			)
		)
		(property "Author" "Antmicro"
			(at 0 0 0)
			(layer "F.Fab")
			(hide yes)
			(effects
				(font
					(size 1 1)
					(thickness 0.15)
				)
			)
		)
		(property "License" "Apache-2.0"
			(at 0 0 0)
			(layer "F.Fab")
			(hide yes)
			(effects
				(font
					(size 1 1)
					(thickness 0.15)
				)
			)
		)
		(property "MPN" "ESD5B5.0ST1G"
			(at 0 0 0)
			(layer "F.Fab")
			(hide yes)
			(effects
				(font
					(size 1 1)
					(thickness 0.15)
				)
			)
		)
		(property "Manufacturer" "ON Semiconductor"
			(at 0 0 0)
			(layer "F.Fab")
			(hide yes)
			(effects
				(font
					(size 1 1)
					(thickness 0.15)
				)
			)
		)
		(sheetname "/Connectors/")
		(sheetfile "connectors.kicad_sch")
		(attr smd)
		(fp_rect
			(start -1 -0.6)
			(end 1 0.6)
			(stroke
				(width 0.05)
				(type solid)
			)
			(fill no)
			(layer "F.CrtYd")
		)
		(fp_line
			(start -0.652 -0.425)
			(end 0.65 -0.425)
			(stroke
				(width 0.15)
				(type solid)
			)
			(layer "F.Fab")
		)
		(fp_line
			(start -0.652 0.423)
			(end -0.652 -0.425)
			(stroke
				(width 0.15)
				(type solid)
			)
			(layer "F.Fab")
		)
		(fp_line
			(start -0.652 0.423)
			(end 0.65 0.423)
			(stroke
				(width 0.15)
				(type solid)
			)
			(layer "F.Fab")
		)
		(fp_line
			(start 0.65 -0.425)
			(end 0.65 0.423)
			(stroke
				(width 0.15)
				(type solid)
			)
			(layer "F.Fab")
		)
		(pad "1" smd roundrect
			(at -0.701 0)
			(size 0.5 0.6)
			(layers "F.Cu" "F.Mask" "F.Paste")
			(roundrect_rratio 0.25)
			(net 1 "GND")
			(pinfunction "C")
			(pintype "passive")
		)
		(pad "2" smd roundrect
			(at 0.699 0)
			(size 0.5 0.6)
			(layers "F.Cu" "F.Mask" "F.Paste")
			(roundrect_rratio 0.25)
			(net 113 "/Connectors/FFC_5V")
			(pinfunction "A")
			(pintype "passive")
		)
	)
	(footprint "antmicro-footprints:TP_SMD_0.75mm"
		(layer "F.Cu")
		(at 136.318 76.3)
		(property "Reference" "TP5"
			(at 0 -0.6 0)
			(layer "F.SilkS")
			(hide yes)
			(effects
				(font
					(size 0.7 0.7)
					(thickness 0.15)
				)
				(justify left bottom)
			)
		)
		(property "Value" "TP_0.75mm_SMD"
			(at 0 1.2 0)
			(layer "F.Fab")
			(effects
				(font
					(size 0.7 0.7)
					(thickness 0.15)
				)
				(justify left bottom)
			)
		)
		(property "Description" "SMT test point"
			(at 0 0 0)
			(layer "F.Fab")
			(hide yes)
			(effects
				(font
					(size 1.27 1.27)
					(thickness 0.15)
				)
			)
		)
		(property "Author" "Antmicro"
			(at 0 0 0)
			(layer "F.Fab")
			(hide yes)
			(effects
				(font
					(size 1 1)
					(thickness 0.15)
				)
			)
		)
		(property "License" "Apache-2.0"
			(at 0 0 0)
			(layer "F.Fab")
			(hide yes)
			(effects
				(font
					(size 1 1)
					(thickness 0.15)
				)
			)
		)
		(property "MPN" ""
			(at 0 0 0)
			(layer "F.Fab")
			(hide yes)
			(effects
				(font
					(size 1 1)
					(thickness 0.15)
				)
			)
		)
		(property "Manufacturer" ""
			(at 0 0 0)
			(layer "F.Fab")
			(hide yes)
			(effects
				(font
					(size 1 1)
					(thickness 0.15)
				)
			)
		)
		(sheetname "/Connectors/")
		(sheetfile "connectors.kicad_sch")
		(fp_circle
			(center 0 0)
			(end 0.475 0)
			(stroke
				(width 0.05)
				(type default)
			)
			(fill no)
			(layer "F.CrtYd")
		)
		(pad "1" smd circle
			(at 0 0)
			(size 0.75 0.75)
			(layers "F.Cu" "F.Mask")
			(net 1 "GND")
			(pinfunction "1")
			(pintype "passive")
		)
	)
	(footprint "antmicro-footprints:R_0402_1005Metric"
		(layer "F.Cu")
		(at 140.89 78.8 135)
		(descr "Resistor SMD 0402")
		(tags "resistor SMD 0402")
		(property "Reference" "R50"
			(at 3.57796 -0.8457 315)
			(unlocked yes)
			(layer "F.SilkS")
			(effects
				(font
					(size 0.7 0.7)
					(thickness 0.15)
				)
				(justify left bottom)
			)
		)
		(property "Value" "R_80k6_0402"
			(at -1.011843 1.772046 135)
			(layer "F.Fab")
			(effects
				(font
					(size 0.7 0.7)
					(thickness 0.15)
				)
				(justify left bottom)
			)
		)
		(property "Datasheet" "https://www.bourns.com/docs/product-datasheets/cr.pdf"
			(at 0 0 135)
			(layer "F.Fab")
			(hide yes)
			(effects
				(font
					(size 1.27 1.27)
					(thickness 0.15)
				)
			)
		)
		(property "Description" "SMD Chip Resistor, 80.6 kohm, ± 1%, 100 mW, 0402 [1005 Metric], Thick Film, Precision"
			(at 0 0 135)
			(layer "F.Fab")
			(hide yes)
			(effects
				(font
					(size 1.27 1.27)
					(thickness 0.15)
				)
			)
		)
		(property "Author" "Antmicro"
			(at 296.328431 34.736745 0)
			(layer "F.Fab")
			(hide yes)
			(effects
				(font
					(size 1 1)
					(thickness 0.15)
				)
			)
		)
		(property "License" "Apache-2.0"
			(at 296.328431 34.736745 0)
			(layer "F.Fab")
			(hide yes)
			(effects
				(font
					(size 1 1)
					(thickness 0.15)
				)
			)
		)
		(property "MPN" "CR0402-FX-8062GLF"
			(at 296.328431 34.736745 0)
			(layer "F.Fab")
			(hide yes)
			(effects
				(font
					(size 1 1)
					(thickness 0.15)
				)
			)
		)
		(property "Manufacturer" "Bourns"
			(at 296.328431 34.736745 0)
			(layer "F.Fab")
			(hide yes)
			(effects
				(font
					(size 1 1)
					(thickness 0.15)
				)
			)
		)
		(property "Tolerance" "1%"
			(at 296.328431 34.736745 0)
			(layer "F.Fab")
			(hide yes)
			(effects
				(font
					(size 1 1)
					(thickness 0.15)
				)
			)
		)
		(property "Val" "80k6"
			(at 296.328431 34.736745 0)
			(layer "F.Fab")
			(hide yes)
			(effects
				(font
					(size 1 1)
					(thickness 0.15)
				)
			)
		)
		(sheetname "/Deserializer/")
		(sheetfile "deserializer.kicad_sch")
		(attr smd exclude_from_pos_files exclude_from_bom dnp)
		(fp_poly
			(pts
				(xy -0.925 -0.47) (xy 0.925 -0.47) (xy 0.925 0.47) (xy -0.925 0.47)
			)
			(stroke
				(width 0.05)
				(type default)
			)
			(fill no)
			(layer "F.CrtYd")
		)
		(fp_poly
			(pts
				(xy -0.5 -0.25) (xy 0.5 -0.25) (xy 0.5 0.25) (xy -0.5 0.25)
			)
			(stroke
				(width 0.15)
				(type solid)
			)
			(fill no)
			(layer "F.Fab")
		)
		(pad "1" smd roundrect
			(at -0.48 0 135)
			(size 0.59 0.64)
			(layers "F.Cu" "F.Mask" "F.Paste")
			(roundrect_rratio 0.25)
			(net 77 "/Deserializer/CFG1")
			(pintype "passive")
		)
		(pad "2" smd roundrect
			(at 0.48 0 135)
			(size 0.59 0.64)
			(layers "F.Cu" "F.Mask" "F.Paste")
			(roundrect_rratio 0.25)
			(net 146 "VDDIO")
			(pintype "passive")
		)
	)
	(footprint "antmicro-footprints:R_0402_1005Metric"
		(layer "F.Cu")
		(at 179.832 58.674 180)
		(descr "Resistor SMD 0402")
		(tags "resistor SMD 0402")
		(property "Reference" "R17"
			(at -3.041644 -0.307453 0)
			(layer "F.SilkS")
			(effects
				(font
					(size 0.7 0.7)
					(thickness 0.15)
				)
				(justify right bottom)
			)
		)
		(property "Value" "R_100k_0402"
			(at -1.011843 1.772047 0)
			(layer "F.Fab")
			(effects
				(font
					(size 0.7 0.7)
					(thickness 0.15)
				)
				(justify right bottom)
			)
		)
		(property "Datasheet" "https://www.bourns.com/docs/product-datasheets/cr.pdf"
			(at 0 0 180)
			(layer "F.Fab")
			(hide yes)
			(effects
				(font
					(size 1.27 1.27)
					(thickness 0.15)
				)
			)
		)
		(property "Description" "SMD Chip Resistor, 100 kohm, ± 1%, 62.5 mW, 0402 [1005 Metric], Thick Film, General Purpose"
			(at 0 0 180)
			(layer "F.Fab")
			(hide yes)
			(effects
				(font
					(size 1.27 1.27)
					(thickness 0.15)
				)
			)
		)
		(property "Author" "Antmicro"
			(at 359.664 117.348 0)
			(layer "F.Fab")
			(hide yes)
			(effects
				(font
					(size 1 1)
					(thickness 0.15)
				)
			)
		)
		(property "License" "Apache-2.0"
			(at 359.664 117.348 0)
			(layer "F.Fab")
			(hide yes)
			(effects
				(font
					(size 1 1)
					(thickness 0.15)
				)
			)
		)
		(property "MPN" "CR0402-FX-1003GLF"
			(at 359.664 117.348 0)
			(layer "F.Fab")
			(hide yes)
			(effects
				(font
					(size 1 1)
					(thickness 0.15)
				)
			)
		)
		(property "Manufacturer" "Bourns"
			(at 359.664 117.348 0)
			(layer "F.Fab")
			(hide yes)
			(effects
				(font
					(size 1 1)
					(thickness 0.15)
				)
			)
		)
		(property "Tolerance" "1%"
			(at 359.664 117.348 0)
			(layer "F.Fab")
			(hide yes)
			(effects
				(font
					(size 1 1)
					(thickness 0.15)
				)
			)
		)
		(property "Val" "100k"
			(at 359.664 117.348 0)
			(layer "F.Fab")
			(hide yes)
			(effects
				(font
					(size 1 1)
					(thickness 0.15)
				)
			)
		)
		(sheetname "/Power/")
		(sheetfile "power.kicad_sch")
		(attr smd)
		(fp_rect
			(start -0.925 -0.47)
			(end 0.925 0.47)
			(stroke
				(width 0.05)
				(type default)
			)
			(fill no)
			(layer "F.CrtYd")
		)
		(fp_rect
			(start -0.5 -0.25)
			(end 0.5 0.25)
			(stroke
				(width 0.15)
				(type solid)
			)
			(fill no)
			(layer "F.Fab")
		)
		(pad "1" smd roundrect
			(at -0.48 0 180)
			(size 0.59 0.64)
			(layers "F.Cu" "F.Mask" "F.Paste")
			(roundrect_rratio 0.25)
			(net 1 "GND")
			(pintype "passive")
		)
		(pad "2" smd roundrect
			(at 0.48 0 180)
			(size 0.59 0.64)
			(layers "F.Cu" "F.Mask" "F.Paste")
			(roundrect_rratio 0.25)
			(net 128 "Net-(Q3-REF)")
			(pintype "passive")
		)
	)
	(footprint "antmicro-footprints:R_0402_1005Metric"
		(layer "F.Cu")
		(at 153.416 73.914 45)
		(descr "Resistor SMD 0402")
		(tags "resistor SMD 0402")
		(property "Reference" "R45"
			(at 4.003639 0.193747 45)
			(layer "F.SilkS")
			(effects
				(font
					(size 0.7 0.7)
					(thickness 0.15)
				)
				(justify left bottom)
			)
		)
		(property "Value" "R_49R9_0402"
			(at -1.011843 1.772046 45)
			(layer "F.Fab")
			(effects
				(font
					(size 0.7 0.7)
					(thickness 0.15)
				)
				(justify left bottom)
			)
		)
		(property "Datasheet" "https://www.bourns.com/docs/product-datasheets/cr.pdf"
			(at 0 0 45)
			(layer "F.Fab")
			(hide yes)
			(effects
				(font
					(size 1.27 1.27)
					(thickness 0.15)
				)
			)
		)
		(property "Description" "SMD Chip Resistor, 49.9 ohm, ± 1%, 62.5 mW, 0402 [1005 Metric], Thick Film, General Purpose"
			(at 0 0 45)
			(layer "F.Fab")
			(hide yes)
			(effects
				(font
					(size 1.27 1.27)
					(thickness 0.15)
				)
			)
		)
		(property "Author" "Antmicro"
			(at 97.199597 -86.832584 0)
			(layer "F.Fab")
			(hide yes)
			(effects
				(font
					(size 1 1)
					(thickness 0.15)
				)
			)
		)
		(property "License" "Apache-2.0"
			(at 97.199597 -86.832584 0)
			(layer "F.Fab")
			(hide yes)
			(effects
				(font
					(size 1 1)
					(thickness 0.15)
				)
			)
		)
		(property "MPN" "CR0402-FX-49R9GLF"
			(at 97.199597 -86.832584 0)
			(layer "F.Fab")
			(hide yes)
			(effects
				(font
					(size 1 1)
					(thickness 0.15)
				)
			)
		)
		(property "Manufacturer" "Bourns"
			(at 97.199597 -86.832584 0)
			(layer "F.Fab")
			(hide yes)
			(effects
				(font
					(size 1 1)
					(thickness 0.15)
				)
			)
		)
		(property "Tolerance" "1%"
			(at 97.199597 -86.832584 0)
			(layer "F.Fab")
			(hide yes)
			(effects
				(font
					(size 1 1)
					(thickness 0.15)
				)
			)
		)
		(property "Val" "49R9"
			(at 97.199597 -86.832584 0)
			(layer "F.Fab")
			(hide yes)
			(effects
				(font
					(size 1 1)
					(thickness 0.15)
				)
			)
		)
		(sheetname "/Deserializer/")
		(sheetfile "deserializer.kicad_sch")
		(attr smd)
		(fp_poly
			(pts
				(xy -0.925 -0.47) (xy 0.925 -0.47) (xy 0.925 0.47) (xy -0.925 0.47)
			)
			(stroke
				(width 0.05)
				(type default)
			)
			(fill no)
			(layer "F.CrtYd")
		)
		(fp_poly
			(pts
				(xy -0.5 -0.25) (xy 0.5 -0.25) (xy 0.5 0.25) (xy -0.5 0.25)
			)
			(stroke
				(width 0.15)
				(type solid)
			)
			(fill no)
			(layer "F.Fab")
		)
		(pad "1" smd roundrect
			(at -0.48 0 45)
			(size 0.59 0.64)
			(layers "F.Cu" "F.Mask" "F.Paste")
			(roundrect_rratio 0.25)
			(net 23 "Net-(C34-Pad2)")
			(pintype "passive")
		)
		(pad "2" smd roundrect
			(at 0.48 0 45)
			(size 0.59 0.64)
			(layers "F.Cu" "F.Mask" "F.Paste")
			(roundrect_rratio 0.25)
			(net 1 "GND")
			(pintype "passive")
		)
	)
	(footprint "antmicro-footprints:C_0402_1005Metric"
		(layer "F.Cu")
		(at 169.431 57.785 -90)
		(descr "Capacitor SMD 0402")
		(tags "capacitor SMD 0402")
		(property "Reference" "C4"
			(at -0.281 -1.177 90)
			(layer "F.SilkS")
			(effects
				(font
					(size 0.7 0.7)
					(thickness 0.15)
				)
				(justify right bottom)
			)
		)
		(property "Value" "C_100n_0402"
			(at -1.022927 2.155213 90)
			(layer "F.Fab")
			(effects
				(font
					(size 0.7 0.7)
					(thickness 0.15)
				)
				(justify right bottom)
			)
		)
		(property "Datasheet" "https://www.murata.com/products/productdetail?partno=GRM155R61H104KE14%23"
			(at 0 0 270)
			(layer "F.Fab")
			(hide yes)
			(effects
				(font
					(size 1.27 1.27)
					(thickness 0.15)
				)
			)
		)
		(property "Description" "SMD Multilayer Ceramic Capacitor, 0.1 µF, 50 V, 0402 [1005 Metric], ± 10%, X5R, GRM Series"
			(at 0 0 270)
			(layer "F.Fab")
			(hide yes)
			(effects
				(font
					(size 1.27 1.27)
					(thickness 0.15)
				)
			)
		)
		(property "Author" "Antmicro"
			(at 111.646 227.216 0)
			(layer "F.Fab")
			(hide yes)
			(effects
				(font
					(size 1 1)
					(thickness 0.15)
				)
			)
		)
		(property "Dielectric" "X5R"
			(at 111.646 227.216 0)
			(layer "F.Fab")
			(hide yes)
			(effects
				(font
					(size 1 1)
					(thickness 0.15)
				)
			)
		)
		(property "License" "Apache-2.0"
			(at 111.646 227.216 0)
			(layer "F.Fab")
			(hide yes)
			(effects
				(font
					(size 1 1)
					(thickness 0.15)
				)
			)
		)
		(property "MPN" "GRM155R61H104KE14D"
			(at 111.646 227.216 0)
			(layer "F.Fab")
			(hide yes)
			(effects
				(font
					(size 1 1)
					(thickness 0.15)
				)
			)
		)
		(property "Manufacturer" "Murata"
			(at 111.646 227.216 0)
			(layer "F.Fab")
			(hide yes)
			(effects
				(font
					(size 1 1)
					(thickness 0.15)
				)
			)
		)
		(property "Val" "100n"
			(at 111.646 227.216 0)
			(layer "F.Fab")
			(hide yes)
			(effects
				(font
					(size 1 1)
					(thickness 0.15)
				)
			)
		)
		(property "Voltage" "50V"
			(at 111.646 227.216 0)
			(layer "F.Fab")
			(hide yes)
			(effects
				(font
					(size 1 1)
					(thickness 0.15)
				)
			)
		)
		(sheetname "/Connectors/")
		(sheetfile "connectors.kicad_sch")
		(attr smd)
		(fp_rect
			(start -0.925 -0.47)
			(end 0.925 0.47)
			(stroke
				(width 0.05)
				(type default)
			)
			(fill no)
			(layer "F.CrtYd")
		)
		(fp_line
			(start -0.494 0.248)
			(end -0.494 -0.25)
			(stroke
				(width 0.15)
				(type solid)
			)
			(layer "F.Fab")
		)
		(fp_line
			(start 0.504 0.248)
			(end -0.494 0.248)
			(stroke
				(width 0.15)
				(type solid)
			)
			(layer "F.Fab")
		)
		(fp_line
			(start -0.494 -0.25)
			(end 0.504 -0.25)
			(stroke
				(width 0.15)
				(type solid)
			)
			(layer "F.Fab")
		)
		(fp_line
			(start 0.504 -0.25)
			(end 0.504 0.248)
			(stroke
				(width 0.15)
				(type solid)
			)
			(layer "F.Fab")
		)
		(pad "1" smd roundrect
			(at -0.48 0 270)
			(size 0.59 0.64)
			(layers "F.Cu" "F.Mask" "F.Paste")
			(roundrect_rratio 0.25)
			(net 1 "GND")
			(pintype "passive")
		)
		(pad "2" smd roundrect
			(at 0.48 0 270)
			(size 0.59 0.64)
			(layers "F.Cu" "F.Mask" "F.Paste")
			(roundrect_rratio 0.25)
			(net 3 "+1V8")
			(pintype "passive")
		)
	)
	(footprint "antmicro-footprints:R_0402_1005Metric"
		(layer "F.Cu")
		(at 127.262 56.642 90)
		(descr "Resistor SMD 0402")
		(tags "resistor SMD 0402")
		(property "Reference" "R24"
			(at -1.122484 1.262 90)
			(layer "F.SilkS")
			(effects
				(font
					(size 0.7 0.7)
					(thickness 0.15)
				)
				(justify left bottom)
			)
		)
		(property "Value" "R_5k1_0402"
			(at -1.011843 1.772047 90)
			(layer "F.Fab")
			(effects
				(font
					(size 0.7 0.7)
					(thickness 0.15)
				)
				(justify left bottom)
			)
		)
		(property "Datasheet" "https://www.bourns.com/docs/product-datasheets/cr.pdf"
			(at 0 0 90)
			(layer "F.Fab")
			(hide yes)
			(effects
				(font
					(size 1.27 1.27)
					(thickness 0.15)
				)
			)
		)
		(property "Description" "SMD Chip Resistor, 5.1 kohm, ± 1%, 63 mW, 0402 [1005 Metric], Thick Film, General Purpose"
			(at 0 0 90)
			(layer "F.Fab")
			(hide yes)
			(effects
				(font
					(size 1.27 1.27)
					(thickness 0.15)
				)
			)
		)
		(property "Author" "Antmicro"
			(at 183.904 -70.62 0)
			(layer "F.Fab")
			(hide yes)
			(effects
				(font
					(size 1 1)
					(thickness 0.15)
				)
			)
		)
		(property "License" "Apache-2.0"
			(at 183.904 -70.62 0)
			(layer "F.Fab")
			(hide yes)
			(effects
				(font
					(size 1 1)
					(thickness 0.15)
				)
			)
		)
		(property "MPN" "CR0402-FX-5101GLF"
			(at 183.904 -70.62 0)
			(layer "F.Fab")
			(hide yes)
			(effects
				(font
					(size 1 1)
					(thickness 0.15)
				)
			)
		)
		(property "Manufacturer" "Bourns"
			(at 183.904 -70.62 0)
			(layer "F.Fab")
			(hide yes)
			(effects
				(font
					(size 1 1)
					(thickness 0.15)
				)
			)
		)
		(property "Tolerance" "1%"
			(at 183.904 -70.62 0)
			(layer "F.Fab")
			(hide yes)
			(effects
				(font
					(size 1 1)
					(thickness 0.15)
				)
			)
		)
		(property "Val" "5k1"
			(at 183.904 -70.62 0)
			(layer "F.Fab")
			(hide yes)
			(effects
				(font
					(size 1 1)
					(thickness 0.15)
				)
			)
		)
		(sheetname "/Power/")
		(sheetfile "power.kicad_sch")
		(attr smd)
		(fp_rect
			(start -0.925 -0.47)
			(end 0.925 0.47)
			(stroke
				(width 0.05)
				(type default)
			)
			(fill no)
			(layer "F.CrtYd")
		)
		(fp_rect
			(start -0.5 -0.25)
			(end 0.5 0.25)
			(stroke
				(width 0.15)
				(type solid)
			)
			(fill no)
			(layer "F.Fab")
		)
		(pad "1" smd roundrect
			(at -0.48 0 90)
			(size 0.59 0.64)
			(layers "F.Cu" "F.Mask" "F.Paste")
			(roundrect_rratio 0.25)
			(net 51 "Net-(L1-Pad2)")
			(pintype "passive")
		)
		(pad "2" smd roundrect
			(at 0.48 0 90)
			(size 0.59 0.64)
			(layers "F.Cu" "F.Mask" "F.Paste")
			(roundrect_rratio 0.25)
			(net 55 "Net-(L5-Pad2)")
			(pintype "passive")
		)
	)
)
